# T6G (Grand Teton) — schematic netlist excerpt (pin names and nets, part order shuffled) for the footprints in the layout excerpt that follows; sources: Cadence DE-HDL packaged netlist, KiCad conversion of 04192023_DAF0TMB3IC0_F0TG_MB_C_brd_V02_OCP.brd

R4213  Q_RES  0 5% CHIP  pkg 0402LF  page 235 : A = FM_THERMAL_ALERT_N ; B = FM_LM75_2_ALERT_N
R5053  Q_RES  1K 1% EMPTY  pkg 0402LF  page 187 : A = P1V5_BAT_OUT ; B = P1V5_BAT_OUT_R

(kicad_pcb
	(version 20260206)
	(generator "pcbnew")
	(generator_version "10.0")
	(general
		(thickness 1.6)
		(legacy_teardrops no)
	)
	(paper "A4")
	(title_block
		(title "04192023_DAF0TMB3IC0_F0TG_MB_C_brd_V02_OCP.brd")
		(comment 1 "Grand Teton / footprints 3946-3947 of 8354")
	)
	(layers
		(0 "F.Cu" signal "TOP")
		(4 "In1.Cu" signal "GND")
		(6 "In2.Cu" signal "IN1")
		(8 "In3.Cu" signal "GND1")
		(10 "In4.Cu" signal "IN2")
		(12 "In5.Cu" signal "GND2")
		(14 "In6.Cu" signal "IN3")
		(16 "In7.Cu" signal "GND3")
		(18 "In8.Cu" signal "VCC")
		(20 "In9.Cu" signal "VCC1")
		(22 "In10.Cu" signal "GND4")
		(24 "In11.Cu" signal "IN4")
		(26 "In12.Cu" signal "GND5")
		(28 "In13.Cu" signal "IN5")
		(30 "In14.Cu" signal "GND6")
		(32 "In15.Cu" signal "IN6")
		(34 "In16.Cu" signal "GND7")
		(2 "B.Cu" signal "BOTTOM")
		(9 "F.Adhes" user "F.Adhesive")
		(11 "B.Adhes" user "B.Adhesive")
		(13 "F.Paste" user "Package Geometry/Pastemask Top")
		(15 "B.Paste" user "Package Geometry/Pastemask Bottom")
		(5 "F.SilkS" user "Ref Des/Silkscreen Top")
		(7 "B.SilkS" user "Ref Des/Silkscreen Bottom")
		(1 "F.Mask" user "Board Geometry/Soldermask Top")
		(3 "B.Mask" user "Board Geometry/Soldermask Bottom")
		(17 "Dwgs.User" user "User.Drawings")
		(19 "Cmts.User" user "User.Comments")
		(21 "Eco1.User" user "User.Eco1")
		(23 "Eco2.User" user "User.Eco2")
		(25 "Edge.Cuts" user "Board Geometry/Outline")
		(27 "Margin" user)
		(31 "F.CrtYd" user "Package Geometry/Place Bound Top")
		(29 "B.CrtYd" user "Package Geometry/Place Bound Bottom")
		(35 "F.Fab" user "Ref Des/Assembly Top")
		(33 "B.Fab" user "Ref Des/Assembly Bottom")
	)
	(footprint ""
		(layer "F.Cu")
		(at 326.330056 -23.826216 -90)
		(property "Reference" "R5053"
			(at 0 0 270)
			(layer "F.SilkS")
			(hide yes)
			(effects
				(font
					(size 1.27 1.27)
				)
			)
		)
		(property "Value" ""
			(at 0 0 270)
			(layer "F.Fab")
			(effects
				(font
					(size 1.27 1.27)
				)
			)
		)
		(duplicate_pad_numbers_are_jumpers no)
		(fp_line
			(start -0.7874 0.4064)
			(end -0.7874 -0.4064)
			(stroke
				(width 0.1524)
				(type default)
			)
			(layer "F.SilkS")
		)
		(fp_line
			(start 0.7874 0.4064)
			(end -0.7874 0.4064)
			(stroke
				(width 0.1524)
				(type default)
			)
			(layer "F.SilkS")
		)
		(fp_line
			(start -0.7874 -0.4064)
			(end 0.7874 -0.4064)
			(stroke
				(width 0.1524)
				(type default)
			)
			(layer "F.SilkS")
		)
		(fp_line
			(start 0.7874 -0.4064)
			(end 0.7874 0.4064)
			(stroke
				(width 0.1524)
				(type default)
			)
			(layer "F.SilkS")
		)
		(fp_line
			(start -0.67945 0.3048)
			(end -0.67945 -0.305054)
			(stroke
				(width 0.1)
				(type default)
			)
			(layer "F.Fab")
		)
		(fp_line
			(start -0.12065 0.3048)
			(end -0.67945 0.3048)
			(stroke
				(width 0.1)
				(type default)
			)
			(layer "F.Fab")
		)
		(fp_line
			(start 0.120396 0.3048)
			(end 0.120396 0.2794)
			(stroke
				(width 0.1)
				(type default)
			)
			(layer "F.Fab")
		)
		(fp_line
			(start 0.67945 0.3048)
			(end 0.120396 0.3048)
			(stroke
				(width 0.1)
				(type default)
			)
			(layer "F.Fab")
		)
		(fp_line
			(start -0.12065 0.2794)
			(end -0.12065 0.3048)
			(stroke
				(width 0.1)
				(type default)
			)
			(layer "F.Fab")
		)
		(fp_line
			(start 0.120396 0.2794)
			(end -0.12065 0.2794)
			(stroke
				(width 0.1)
				(type default)
			)
			(layer "F.Fab")
		)
		(fp_line
			(start -0.12065 -0.2794)
			(end 0.12065 -0.2794)
			(stroke
				(width 0.1)
				(type default)
			)
			(layer "F.Fab")
		)
		(fp_line
			(start 0.12065 -0.2794)
			(end 0.12065 -0.3048)
			(stroke
				(width 0.1)
				(type default)
			)
			(layer "F.Fab")
		)
		(fp_line
			(start 0.12065 -0.3048)
			(end 0.67945 -0.3048)
			(stroke
				(width 0.1)
				(type default)
			)
			(layer "F.Fab")
		)
		(fp_line
			(start 0.67945 -0.3048)
			(end 0.67945 0.3048)
			(stroke
				(width 0.1)
				(type default)
			)
			(layer "F.Fab")
		)
		(fp_line
			(start -0.67945 -0.305054)
			(end -0.12065 -0.305054)
			(stroke
				(width 0.1)
				(type default)
			)
			(layer "F.Fab")
		)
		(fp_line
			(start -0.12065 -0.305054)
			(end -0.12065 -0.2794)
			(stroke
				(width 0.1)
				(type default)
			)
			(layer "F.Fab")
		)
		(pad "1" smd circle
			(at -0.40005 0 270)
			(size 0 0)
			(layers "F.Cu" "F.Mask" "F.Paste")
			(net "P1V5_BAT_OUT")
		)
		(pad "2" smd circle
			(at 0.40005 0 270)
			(size 0 0)
			(layers "F.Cu" "F.Mask" "F.Paste")
			(net "P1V5_BAT_OUT_R")
		)
	)
	(footprint ""
		(layer "F.Cu")
		(at 100.285296 -412.931102 90)
		(property "Reference" "R4213"
			(at 0 0 90)
			(layer "F.SilkS")
			(hide yes)
			(effects
				(font
					(size 1.27 1.27)
				)
			)
		)
		(property "Value" ""
			(at 0 0 90)
			(layer "F.Fab")
			(effects
				(font
					(size 1.27 1.27)
				)
			)
		)
		(duplicate_pad_numbers_are_jumpers no)
		(fp_line
			(start 0.7874 -0.4064)
			(end 0.7874 0.4064)
			(stroke
				(width 0.1524)
				(type default)
			)
			(layer "F.SilkS")
		)
		(fp_line
			(start -0.7874 -0.4064)
			(end 0.7874 -0.4064)
			(stroke
				(width 0.1524)
				(type default)
			)
			(layer "F.SilkS")
		)
		(fp_line
			(start 0.7874 0.4064)
			(end -0.7874 0.4064)
			(stroke
				(width 0.1524)
				(type default)
			)
			(layer "F.SilkS")
		)
		(fp_line
			(start -0.7874 0.4064)
			(end -0.7874 -0.4064)
			(stroke
				(width 0.1524)
				(type default)
			)
			(layer "F.SilkS")
		)
		(fp_line
			(start -0.12065 -0.305054)
			(end -0.12065 -0.2794)
			(stroke
				(width 0.1)
				(type default)
			)
			(layer "F.Fab")
		)
		(fp_line
			(start -0.67945 -0.305054)
			(end -0.12065 -0.305054)
			(stroke
				(width 0.1)
				(type default)
			)
			(layer "F.Fab")
		)
		(fp_line
			(start 0.67945 -0.3048)
			(end 0.67945 0.3048)
			(stroke
				(width 0.1)
				(type default)
			)
			(layer "F.Fab")
		)
		(fp_line
			(start 0.12065 -0.3048)
			(end 0.67945 -0.3048)
			(stroke
				(width 0.1)
				(type default)
			)
			(layer "F.Fab")
		)
		(fp_line
			(start 0.12065 -0.2794)
			(end 0.12065 -0.3048)
			(stroke
				(width 0.1)
				(type default)
			)
			(layer "F.Fab")
		)
		(fp_line
			(start -0.12065 -0.2794)
			(end 0.12065 -0.2794)
			(stroke
				(width 0.1)
				(type default)
			)
			(layer "F.Fab")
		)
		(fp_line
			(start 0.120396 0.2794)
			(end -0.12065 0.2794)
			(stroke
				(width 0.1)
				(type default)
			)
			(layer "F.Fab")
		)
		(fp_line
			(start -0.12065 0.2794)
			(end -0.12065 0.3048)
			(stroke
				(width 0.1)
				(type default)
			)
			(layer "F.Fab")
		)
		(fp_line
			(start 0.67945 0.3048)
			(end 0.120396 0.3048)
			(stroke
				(width 0.1)
				(type default)
			)
			(layer "F.Fab")
		)
		(fp_line
			(start 0.120396 0.3048)
			(end 0.120396 0.2794)
			(stroke
				(width 0.1)
				(type default)
			)
			(layer "F.Fab")
		)
		(fp_line
			(start -0.12065 0.3048)
			(end -0.67945 0.3048)
			(stroke
				(width 0.1)
				(type default)
			)
			(layer "F.Fab")
		)
		(fp_line
			(start -0.67945 0.3048)
			(end -0.67945 -0.305054)
			(stroke
				(width 0.1)
				(type default)
			)
			(layer "F.Fab")
		)
		(pad "1" smd circle
			(at -0.40005 0 90)
			(size 0 0)
			(layers "F.Cu" "F.Mask" "F.Paste")
			(net "FM_THERMAL_ALERT_N")
		)
		(pad "2" smd circle
			(at 0.40005 0 90)
			(size 0 0)
			(layers "F.Cu" "F.Mask" "F.Paste")
			(net "FM_LM75_2_ALERT_N")
		)
	)
)
